(kicad_pcb
	(version 20241229)
	(generator "pcbnew")
	(generator_version "9.0")
	(general
		(thickness 1.61)
		(legacy_teardrops no)
	)
	(paper "A3")
	(title_block
		(title "RDIMM DDR5 Tester")
		(date "2026-05-21")
		(rev "2.2.0")
		(company "Antmicro")
		(comment 9 "footprints 138-141 of 796")
	)
	(layers
		(0 "F.Cu" signal)
		(4 "In1.Cu" power)
		(6 "In2.Cu" mixed)
		(8 "In3.Cu" power)
		(10 "In4.Cu" mixed)
		(12 "In5.Cu" power)
		(14 "In6.Cu" mixed)
		(16 "In7.Cu" power)
		(18 "In8.Cu" power)
		(20 "In9.Cu" mixed)
		(22 "In10.Cu" power)
		(2 "B.Cu" signal)
		(9 "F.Adhes" user "F.Adhesive")
		(11 "B.Adhes" user "B.Adhesive")
		(13 "F.Paste" user)
		(15 "B.Paste" user)
		(5 "F.SilkS" user "F.Silkscreen")
		(7 "B.SilkS" user "B.Silkscreen")
		(1 "F.Mask" user)
		(3 "B.Mask" user)
		(17 "Dwgs.User" user "User.Drawings")
		(19 "Cmts.User" user "User.Comments")
		(21 "Eco1.User" user "User.Eco1")
		(23 "Eco2.User" user "User.Eco2")
		(25 "Edge.Cuts" user)
		(27 "Margin" user)
		(31 "F.CrtYd" user "F.Courtyard")
		(29 "B.CrtYd" user "B.Courtyard")
		(35 "F.Fab" user)
		(33 "B.Fab" user)
	)
	(footprint "antmicro-footprints:R_0402_1005Metric"
		(layer "F.Cu")
		(at 257.79 143.185 -90)
		(descr "Resistor SMD 0402")
		(tags "resistor SMD 0402")
		(property "Reference" "R78"
			(at -1.085 0.54 90)
			(layer "F.SilkS")
			(effects
				(font
					(size 0.7 0.7)
					(thickness 0.15)
				)
				(justify right bottom)
			)
		)
		(property "Value" "R_4k7_0402"
			(at -1.011843 1.772047 90)
			(layer "F.Fab")
			(effects
				(font
					(size 0.7 0.7)
					(thickness 0.15)
				)
				(justify right bottom)
			)
		)
		(property "Datasheet" "https://www.bourns.com/docs/product-datasheets/cr.pdf"
			(at 0 0 270)
			(layer "F.Fab")
			(hide yes)
			(effects
				(font
					(size 1.27 1.27)
					(thickness 0.15)
				)
			)
		)
		(property "Manufacturer" "Bourns"
			(at 0 0 270)
			(unlocked yes)
			(layer "F.Fab")
			(hide yes)
			(effects
				(font
					(size 1 1)
					(thickness 0.15)
				)
			)
		)
		(property "MPN" "CR0402-FX-4701GLF"
			(at 0 0 270)
			(unlocked yes)
			(layer "F.Fab")
			(hide yes)
			(effects
				(font
					(size 1 1)
					(thickness 0.15)
				)
			)
		)
		(property "Val" "4k7"
			(at 0 0 270)
			(unlocked yes)
			(layer "F.Fab")
			(hide yes)
			(effects
				(font
					(size 1 1)
					(thickness 0.15)
				)
			)
		)
		(property "License" "Apache-2.0"
			(at 0 0 270)
			(unlocked yes)
			(layer "F.Fab")
			(hide yes)
			(effects
				(font
					(size 1 1)
					(thickness 0.15)
				)
			)
		)
		(property "Author" "Antmicro"
			(at 0 0 270)
			(unlocked yes)
			(layer "F.Fab")
			(hide yes)
			(effects
				(font
					(size 1 1)
					(thickness 0.15)
				)
			)
		)
		(property "Tolerance" "1%"
			(at 0 0 270)
			(unlocked yes)
			(layer "F.Fab")
			(hide yes)
			(effects
				(font
					(size 1 1)
					(thickness 0.15)
				)
			)
		)
		(sheetname "/DDR5 RDIMM/")
		(sheetfile "ddr5-rdimm.kicad_sch")
		(attr smd)
		(fp_rect
			(start -0.925 -0.47)
			(end 0.925 0.47)
			(stroke
				(width 0.05)
				(type default)
			)
			(fill no)
			(layer "F.CrtYd")
		)
		(fp_rect
			(start -0.5 -0.25)
			(end 0.5 0.25)
			(stroke
				(width 0.15)
				(type solid)
			)
			(fill no)
			(layer "F.Fab")
		)
		(fp_text user "Author: Antmicro"
			(at -0.95 4.169 270)
			(layer "F.Fab")
			(effects
				(font
					(size 0.7 0.7)
					(thickness 0.15)
				)
				(justify left bottom)
			)
		)
		(fp_text user "${REFERENCE}"
			(at -0.95 3.168 270)
			(layer "F.Fab")
			(effects
				(font
					(size 0.7 0.7)
					(thickness 0.15)
				)
				(justify left bottom)
			)
		)
		(fp_text user "License: Apache-2.0"
			(at -0.95 5.169 270)
			(layer "F.Fab")
			(effects
				(font
					(size 0.7 0.7)
					(thickness 0.15)
				)
				(justify left bottom)
			)
		)
		(pad "1" smd roundrect
			(at -0.48 0 270)
			(size 0.59 0.64)
			(layers "F.Cu" "F.Mask" "F.Paste")
			(roundrect_rratio 0.25)
			(net 151 "+3V3")
			(pintype "passive")
		)
		(pad "2" smd roundrect
			(at 0.48 0 270)
			(size 0.59 0.64)
			(layers "F.Cu" "F.Mask" "F.Paste")
			(roundrect_rratio 0.25)
			(net 69 "HOT_SWAP_BUTTON")
			(pintype "passive")
		)
	)
	(footprint "antmicro-footprints:Conn_JST_SH_1x2_BM02B-SRSS-TB-LF-SN"
		(layer "F.Cu")
		(at 239.55 119.92 180)
		(property "Reference" "J17"
			(at 0.31 -3.915 0)
			(layer "F.SilkS")
			(effects
				(font
					(size 0.7 0.7)
					(thickness 0.15)
				)
				(justify right bottom)
			)
		)
		(property "Value" "JST_SH_1x2_BM02B-SRSS-TB-LF-SN"
			(at -2.3 4 0)
			(layer "F.Fab")
			(effects
				(font
					(size 0.7 0.7)
					(thickness 0.15)
				)
				(justify right bottom)
			)
		)
		(property "Datasheet" "https://www.jst-mfg.com/product/pdf/eng/eSH.pdf"
			(at 0 0 180)
			(layer "F.Fab")
			(hide yes)
			(effects
				(font
					(size 1.27 1.27)
					(thickness 0.15)
				)
			)
		)
		(property "MPN" "BM02B-SRSS-TB(LF)(SN)"
			(at 0 0 180)
			(unlocked yes)
			(layer "F.Fab")
			(hide yes)
			(effects
				(font
					(size 1 1)
					(thickness 0.15)
				)
			)
		)
		(property "Manufacturer" "JST Automotive Connectors"
			(at 0 0 180)
			(unlocked yes)
			(layer "F.Fab")
			(hide yes)
			(effects
				(font
					(size 1 1)
					(thickness 0.15)
				)
			)
		)
		(property "Author" "Antmicro"
			(at 0 0 180)
			(unlocked yes)
			(layer "F.Fab")
			(hide yes)
			(effects
				(font
					(size 1 1)
					(thickness 0.15)
				)
			)
		)
		(property "License" "Apache-2.0"
			(at 0 0 180)
			(unlocked yes)
			(layer "F.Fab")
			(hide yes)
			(effects
				(font
					(size 1 1)
					(thickness 0.15)
				)
			)
		)
		(sheetname "/Supply/")
		(sheetfile "supply.kicad_sch")
		(attr smd)
		(fp_line
			(start 1.9 -0.88)
			(end 1.9 0.88)
			(stroke
				(width 0.15)
				(type solid)
			)
			(layer "F.SilkS")
		)
		(fp_line
			(start -1.1 2.1)
			(end 0 2.1)
			(stroke
				(width 0.15)
				(type solid)
			)
			(layer "F.SilkS")
		)
		(fp_line
			(start -1.1 2.1)
			(end -1.1 1.22)
			(stroke
				(width 0.15)
				(type solid)
			)
			(layer "F.SilkS")
		)
		(fp_line
			(start -1.1 -1.22)
			(end -1.1 -2.1)
			(stroke
				(width 0.15)
				(type solid)
			)
			(layer "F.SilkS")
		)
		(fp_line
			(start -1.1 -2.1)
			(end 0 -2.1)
			(stroke
				(width 0.15)
				(type solid)
			)
			(layer "F.SilkS")
		)
		(fp_circle
			(center -1.6 -1.2)
			(end -1.55 -1.2)
			(stroke
				(width 0.15)
				(type solid)
			)
			(fill yes)
			(layer "F.SilkS")
		)
		(fp_rect
			(start -2.05 -2.95)
			(end 2.05 2.95)
			(stroke
				(width 0.05)
				(type solid)
			)
			(fill no)
			(layer "F.CrtYd")
		)
		(fp_rect
			(start -1.8 -2)
			(end 1.8 2)
			(stroke
				(width 0.15)
				(type solid)
			)
			(fill no)
			(layer "F.Fab")
		)
		(fp_text user "${REFERENCE}"
			(at -2.3 7.2 180)
			(layer "F.Fab")
			(effects
				(font
					(size 0.7 0.7)
					(thickness 0.15)
				)
				(justify left bottom)
			)
		)
		(fp_text user "License: Apache-2.0"
			(at -2.3 8.4 180)
			(layer "F.Fab")
			(effects
				(font
					(size 0.7 0.7)
					(thickness 0.15)
				)
				(justify left bottom)
			)
		)
		(fp_text user "Author: Antmicro"
			(at -2.3 6 180)
			(layer "F.Fab")
			(effects
				(font
					(size 0.7 0.7)
					(thickness 0.15)
				)
				(justify left bottom)
			)
		)
		(pad "1" smd roundrect
			(at -1.325 -0.5 90)
			(size 0.6 1.55)
			(layers "F.Cu" "F.Mask" "F.Paste")
			(roundrect_rratio 0.25)
			(net 811 "/Supply/heater")
			(pintype "passive")
		)
		(pad "2" smd roundrect
			(at -1.325 0.5 270)
			(size 0.6 1.55)
			(layers "F.Cu" "F.Mask" "F.Paste")
			(roundrect_rratio 0.25)
			(net 1 "GND")
			(pintype "passive")
		)
		(pad "MP" smd roundrect
			(at 1.2 -1.8 270)
			(size 1.2 1.8)
			(layers "F.Cu" "F.Mask" "F.Paste")
			(roundrect_rratio 0.25)
			(net 1 "GND")
			(pintype "passive")
		)
		(pad "MP" smd roundrect
			(at 1.2 1.8 270)
			(size 1.2 1.8)
			(layers "F.Cu" "F.Mask" "F.Paste")
			(roundrect_rratio 0.25)
			(net 1 "GND")
			(pintype "passive")
		)
	)
	(footprint "antmicro-footprints:SC70-3"
		(layer "F.Cu")
		(at 115.1 115.1 90)
		(property "Reference" "Q2"
			(at -0.45 -0.775 0)
			(layer "F.SilkS")
			(effects
				(font
					(size 0.7 0.7)
					(thickness 0.15)
				)
				(justify left bottom)
			)
		)
		(property "Value" "BSS138PW"
			(at 0 2.3 90)
			(layer "F.Fab")
			(effects
				(font
					(size 0.7 0.7)
					(thickness 0.15)
				)
				(justify left bottom)
			)
		)
		(property "Datasheet" "https://assets.nexperia.com/documents/data-sheet/BSS138PW.pdf"
			(at 0 0 90)
			(layer "F.Fab")
			(hide yes)
			(effects
				(font
					(size 1.27 1.27)
					(thickness 0.15)
				)
			)
		)
		(property "MPN" "BSS138PW"
			(at 0 0 90)
			(unlocked yes)
			(layer "F.Fab")
			(hide yes)
			(effects
				(font
					(size 1 1)
					(thickness 0.15)
				)
			)
		)
		(property "Manufacturer" "Nexperia"
			(at 0 0 90)
			(unlocked yes)
			(layer "F.Fab")
			(hide yes)
			(effects
				(font
					(size 1 1)
					(thickness 0.15)
				)
			)
		)
		(property "Author" "Antmicro"
			(at 0 0 90)
			(unlocked yes)
			(layer "F.Fab")
			(hide yes)
			(effects
				(font
					(size 1 1)
					(thickness 0.15)
				)
			)
		)
		(property "License" "Apache-2.0"
			(at 0 0 90)
			(unlocked yes)
			(layer "F.Fab")
			(hide yes)
			(effects
				(font
					(size 1 1)
					(thickness 0.15)
				)
			)
		)
		(sheetname "/FPGA Config/")
		(sheetfile "fpga-config.kicad_sch")
		(attr smd)
		(fp_line
			(start -0.3 -1)
			(end 0.627 -0.999)
			(stroke
				(width 0.15)
				(type solid)
			)
			(layer "F.SilkS")
		)
		(fp_line
			(start 0.627 -0.6)
			(end 0.627 -0.999)
			(stroke
				(width 0.15)
				(type solid)
			)
			(layer "F.SilkS")
		)
		(fp_line
			(start 0.627 0.6)
			(end 0.627 1.001)
			(stroke
				(width 0.15)
				(type solid)
			)
			(layer "F.SilkS")
		)
		(fp_line
			(start -0.3 1)
			(end 0.627 1.001)
			(stroke
				(width 0.15)
				(type solid)
			)
			(layer "F.SilkS")
		)
		(fp_line
			(start 0.9 -1.3)
			(end 0.9 -0.4)
			(stroke
				(width 0.05)
				(type solid)
			)
			(layer "F.CrtYd")
		)
		(fp_line
			(start -0.9 -1.3)
			(end 0.9 -1.3)
			(stroke
				(width 0.05)
				(type solid)
			)
			(layer "F.CrtYd")
		)
		(fp_line
			(start -0.9 -1.3)
			(end -0.9 -1)
			(stroke
				(width 0.05)
				(type solid)
			)
			(layer "F.CrtYd")
		)
		(fp_line
			(start -0.9 -1)
			(end -1.4 -1)
			(stroke
				(width 0.05)
				(type solid)
			)
			(layer "F.CrtYd")
		)
		(fp_line
			(start 1.4 -0.4)
			(end 1.4 0.4)
			(stroke
				(width 0.05)
				(type solid)
			)
			(layer "F.CrtYd")
		)
		(fp_line
			(start 0.9 -0.4)
			(end 1.4 -0.4)
			(stroke
				(width 0.05)
				(type solid)
			)
			(layer "F.CrtYd")
		)
		(fp_line
			(start 1.4 0.4)
			(end 0.9 0.4)
			(stroke
				(width 0.05)
				(type solid)
			)
			(layer "F.CrtYd")
		)
		(fp_line
			(start 0.9 0.4)
			(end 0.9 1.3)
			(stroke
				(width 0.05)
				(type solid)
			)
			(layer "F.CrtYd")
		)
		(fp_line
			(start -0.9 1)
			(end -1.4 1)
			(stroke
				(width 0.05)
				(type solid)
			)
			(layer "F.CrtYd")
		)
		(fp_line
			(start -1.4 1)
			(end -1.4 -1)
			(stroke
				(width 0.05)
				(type solid)
			)
			(layer "F.CrtYd")
		)
		(fp_line
			(start 0.9 1.3)
			(end -0.9 1.3)
			(stroke
				(width 0.05)
				(type solid)
			)
			(layer "F.CrtYd")
		)
		(fp_line
			(start -0.9 1.3)
			(end -0.9 1)
			(stroke
				(width 0.05)
				(type solid)
			)
			(layer "F.CrtYd")
		)
		(fp_rect
			(start -0.623 -0.999)
			(end 0.627 1.001)
			(stroke
				(width 0.15)
				(type solid)
			)
			(fill no)
			(layer "F.Fab")
		)
		(fp_text user "${REFERENCE}"
			(at -1.45 4.783 90)
			(layer "F.Fab")
			(effects
				(font
					(size 0.7 0.7)
					(thickness 0.15)
				)
				(justify left bottom)
			)
		)
		(fp_text user "Author: Antmicro"
			(at -1.45 5.782 90)
			(layer "F.Fab")
			(effects
				(font
					(size 0.7 0.7)
					(thickness 0.15)
				)
				(justify left bottom)
			)
		)
		(fp_text user "License: Apache-2.0"
			(at -1.45 6.782 90)
			(layer "F.Fab")
			(effects
				(font
					(size 0.7 0.7)
					(thickness 0.15)
				)
				(justify left bottom)
			)
		)
		(pad "1" smd rect
			(at -1.051 -0.65 180)
			(size 0.6 0.6)
			(layers "F.Cu" "F.Mask" "F.Paste")
			(net 341 "/FPGA Config/INIT_B")
			(pinfunction "G")
			(pintype "passive")
		)
		(pad "2" smd rect
			(at -1.051 0.65 180)
			(size 0.6 0.6)
			(layers "F.Cu" "F.Mask" "F.Paste")
			(net 1 "GND")
			(pinfunction "S")
			(pintype "passive")
		)
		(pad "3" smd rect
			(at 1.05 0 180)
			(size 0.6 0.6)
			(layers "F.Cu" "F.Mask" "F.Paste")
			(net 270 "Net-(Q2-D)")
			(pinfunction "D")
			(pintype "passive")
		)
	)
	(footprint "antmicro-footprints:C_0402_1005Metric"
		(layer "F.Cu")
		(at 155.67 159.154999 90)
		(descr "Capacitor SMD 0402")
		(tags "capacitor SMD 0402")
		(property "Reference" "C286"
			(at -1.025 -0.88 90)
			(layer "F.SilkS")
			(effects
				(font
					(size 0.7 0.7)
					(thickness 0.15)
				)
				(justify left bottom)
			)
		)
		(property "Value" "C_100n_0402"
			(at -1.022927 2.155213 90)
			(layer "F.Fab")
			(effects
				(font
					(size 0.7 0.7)
					(thickness 0.15)
				)
				(justify left bottom)
			)
		)
		(property "Datasheet" "https://www.murata.com/products/productdetail?partno=GRM155R61H104KE14%23"
			(at 0 0 90)
			(layer "F.Fab")
			(hide yes)
			(effects
				(font
					(size 1.27 1.27)
					(thickness 0.15)
				)
			)
		)
		(property "MPN" "GRM155R61H104KE14D"
			(at 0 0 90)
			(unlocked yes)
			(layer "F.Fab")
			(hide yes)
			(effects
				(font
					(size 1 1)
					(thickness 0.15)
				)
			)
		)
		(property "Manufacturer" "Murata"
			(at 0 0 90)
			(unlocked yes)
			(layer "F.Fab")
			(hide yes)
			(effects
				(font
					(size 1 1)
					(thickness 0.15)
				)
			)
		)
		(property "License" "Apache-2.0"
			(at 0 0 90)
			(unlocked yes)
			(layer "F.Fab")
			(hide yes)
			(effects
				(font
					(size 1 1)
					(thickness 0.15)
				)
			)
		)
		(property "Author" "Antmicro"
			(at 0 0 90)
			(unlocked yes)
			(layer "F.Fab")
			(hide yes)
			(effects
				(font
					(size 1 1)
					(thickness 0.15)
				)
			)
		)
		(property "Val" "100n"
			(at 0 0 90)
			(unlocked yes)
			(layer "F.Fab")
			(hide yes)
			(effects
				(font
					(size 1 1)
					(thickness 0.15)
				)
			)
		)
		(property "Voltage" "50V"
			(at 0 0 90)
			(unlocked yes)
			(layer "F.Fab")
			(hide yes)
			(effects
				(font
					(size 1 1)
					(thickness 0.15)
				)
			)
		)
		(property "Dielectric" "X5R"
			(at 0 0 90)
			(unlocked yes)
			(layer "F.Fab")
			(hide yes)
			(effects
				(font
					(size 1 1)
					(thickness 0.15)
				)
			)
		)
		(property "Public" ""
			(at 0 0 90)
			(unlocked yes)
			(layer "F.Fab")
			(hide yes)
			(effects
				(font
					(size 1 1)
					(thickness 0.15)
				)
			)
		)
		(sheetname "/FPGA MGT Interface/")
		(sheetfile "fpga-mgt.kicad_sch")
		(attr smd)
		(fp_rect
			(start -0.925 -0.47)
			(end 0.925 0.47)
			(stroke
				(width 0.05)
				(type default)
			)
			(fill no)
			(layer "F.CrtYd")
		)
		(fp_line
			(start 0.504 -0.25)
			(end 0.504 0.248)
			(stroke
				(width 0.15)
				(type solid)
			)
			(layer "F.Fab")
		)
		(fp_line
			(start -0.494 -0.25)
			(end 0.504 -0.25)
			(stroke
				(width 0.15)
				(type solid)
			)
			(layer "F.Fab")
		)
		(fp_line
			(start 0.504 0.248)
			(end -0.494 0.248)
			(stroke
				(width 0.15)
				(type solid)
			)
			(layer "F.Fab")
		)
		(fp_line
			(start -0.494 0.248)
			(end -0.494 -0.25)
			(stroke
				(width 0.15)
				(type solid)
			)
			(layer "F.Fab")
		)
		(fp_text user "${REFERENCE}"
			(at -0.939 4.599 90)
			(layer "F.Fab")
			(effects
				(font
					(size 0.7 0.7)
					(thickness 0.15)
				)
				(justify left bottom)
			)
		)
		(fp_text user "License: Apache-2.0"
			(at -0.939 5.799 90)
			(layer "F.Fab")
			(effects
				(font
					(size 0.7 0.7)
					(thickness 0.15)
				)
				(justify left bottom)
			)
		)
		(fp_text user "Author: Antmicro"
			(at -0.939 3.399 90)
			(layer "F.Fab")
			(effects
				(font
					(size 0.7 0.7)
					(thickness 0.15)
				)
				(justify left bottom)
			)
		)
		(pad "1" smd roundrect
			(at -0.48 0 90)
			(size 0.59 0.64)
			(layers "F.Cu" "F.Mask" "F.Paste")
			(roundrect_rratio 0.25)
			(net 151 "+3V3")
			(pintype "passive")
		)
		(pad "2" smd roundrect
			(at 0.48 0 90)
			(size 0.59 0.64)
			(layers "F.Cu" "F.Mask" "F.Paste")
			(roundrect_rratio 0.25)
			(net 1 "GND")
			(pintype "passive")
		)
	)
)
